# S9S_MB_2U (Grand Teton) — schematic netlist excerpt (pin names and nets, part order shuffled) for the footprints in the layout excerpt that follows; sources: Cadence DE-HDL packaged netlist, KiCad conversion of 03242023_DA0F0TMBIJ0_F0T_Motherboard_J_brd_V01_OCP.brd

J26  SCONN288_ADR50017P087CC  SCONN288_ADR50017-P087CC IO  pkg DDR288S_1-1VXB  page 107
  VIN_BULK0  = P12V_S3_AUX_CPU1_NVDIMM
  RFU0  = TP_CHE_CPU1_DIMM2_FRU_0
  VIN_MGMT  = P3V3_AUX
  HSCL  = I3C_SPD_DDREFGH_CPU1_LVC1_SCL_1
  HSDA  = I3C_SPD_DDREFGH_CPU1_LVC1_SDA
  VSS0  = GND
  DQ0_A  = M_E_CPU1_SA_DQ<0>
  VSS1  = GND
  DQ1_A  = M_E_CPU1_SA_DQ<1>
  VSS2  = GND
  DQS0_A_T  = M_E_CPU1_SA_DQS_DP<0>
  DQS0_A_C  = M_E_CPU1_SA_DQS_DN<0>
  VSS3  = GND
  DQ4_A  = M_E_CPU1_SA_DQ<4>
  VSS4  = GND
  DQ5_A  = M_E_CPU1_SA_DQ<5>
  VSS5  = GND
  DQ8_A  = M_E_CPU1_SA_DQ<8>
  VSS6  = GND
  DQ9_A  = M_E_CPU1_SA_DQ<9>
  VSS7  = GND
  DQS1_A_T  = M_E_CPU1_SA_DQS_DP<1>
  DQS1_A_C  = M_E_CPU1_SA_DQS_DN<1>
  VSS8  = GND
  DQ12_A  = M_E_CPU1_SA_DQ<12>
  VSS9  = GND
  DQ13_A  = M_E_CPU1_SA_DQ<13>
  VSS10  = GND
  DQ16_A  = M_E_CPU1_SA_DQ<16>
  VSS11  = GND
  DQ17_A  = M_E_CPU1_SA_DQ<17>
  VSS12  = GND
  DQS2_A_T  = M_E_CPU1_SA_DQS_DP<2>
  DQS2_A_C  = M_E_CPU1_SA_DQS_DN<2>
  VSS13  = GND
  DQ20_A  = M_E_CPU1_SA_DQ<20>
  VSS14  = GND
  DQ21_A  = M_E_CPU1_SA_DQ<21>
  VSS15  = GND
  DQ24_A  = M_E_CPU1_SA_DQ<24>
  VSS16  = GND
  DQ25_A  = M_E_CPU1_SA_DQ<25>
  VSS17  = GND
  DQS3_A_T  = M_E_CPU1_SA_DQS_DP<3>
  DQS3_A_C  = M_E_CPU1_SA_DQS_DN<3>
  VSS18  = GND
  DQ28_A  = M_E_CPU1_SA_DQ<28>
  VSS19  = GND
  DQ29_A  = M_E_CPU1_SA_DQ<29>
  VSS20  = GND
  CB0_A  = M_E_CPU1_SA_CB<0>
  VSS21  = GND
  CB1_A  = M_E_CPU1_SA_CB<1>
  VSS22  = GND
  DQS4_A_T  = M_E_CPU1_SA_DQS_DP<4>
  DQS4_A_C  = M_E_CPU1_SA_DQS_DN<4>
  VSS23  = GND
  CB4_A  = M_E_CPU1_SA_CB<4>
  VSS24  = GND
  CB5_A  = M_E_CPU1_SA_CB<5>
  VSS25  = GND
  ALERT_N  = M_E_CPU1_ALERT_N
  VSS26  = GND
  CS0_A_N  = M_E_CPU1_SA_CS_N<2>
  VSS27  = GND
  CA0_A  = M_E_CPU1_SA_CA<0>
  VSS28  = GND
  CA2_A  = M_E_CPU1_SA_CA<2>
  VSS29  = GND
  CA4_A  = M_E_CPU1_SA_CA<4>
  VSS30  = GND
  CA6_A  = M_E_CPU1_SA_CA<6>
  VSS31  = GND
  PAR_A  = M_E_CPU1_SA_PAR
  VSS32  = GND
  CA0_B  = M_E_CPU1_SB_CA<0>
  VSS33  = GND
  CA2_B  = M_E_CPU1_SB_CA<2>
  VSS34  = GND
  CA4_B  = M_E_CPU1_SB_CA<4>
  VSS35  = GND
  CA6_B  = M_E_CPU1_SB_CA<6>
  VSS36  = GND
  CS0_B_N  = M_E_CPU1_SB_CS_N<2>
  VSS37  = GND
  \lbd||rsp_a_n\  = M_E_CPU1_SA_RSP<1>
  \lbs||rsp_b_n\  = M_E_CPU1_SB_RSP<1>
  VSS38  = GND
  CB4_B  = M_E_CPU1_SB_CB<4>
  VSS39  = GND
  CB5_B  = M_E_CPU1_SB_CB<5>
  VSS40  = GND
  \dqs9_b_t||tdqs9_b_t||dbi4_b_n\  = M_E_CPU1_SB_DQS_DP<9>
  \dqs9_b_c||tdqs9_b_c\  = M_E_CPU1_SB_DQS_DN<9>
  VSS41  = GND
  CB0_B  = M_E_CPU1_SB_CB<0>
  VSS42  = GND
  CB1_B  = M_E_CPU1_SB_CB<1>
  VSS43  = GND
  DQ0_B  = M_E_CPU1_SB_DQ<0>
  VSS44  = GND
  DQ1_B  = M_E_CPU1_SB_DQ<1>
  VSS45  = GND
  DQS0_B_T  = M_E_CPU1_SB_DQS_DP<0>
  DQS0_B_C  = M_E_CPU1_SB_DQS_DN<0>
  VSS46  = GND
  DQ4_B  = M_E_CPU1_SB_DQ<4>
  VSS47  = GND
  DQ5_B  = M_E_CPU1_SB_DQ<5>
  VSS48  = GND
  DQ8_B  = M_E_CPU1_SB_DQ<8>
  VSS49  = GND
  DQ9_B  = M_E_CPU1_SB_DQ<9>
  VSS50  = GND
  DQS1_B_T  = M_E_CPU1_SB_DQS_DP<1>
  DQS1_B_C  = M_E_CPU1_SB_DQS_DN<1>
  VSS51  = GND
  DQ12_B  = M_E_CPU1_SB_DQ<12>
  VSS52  = GND
  DQ13_B  = M_E_CPU1_SB_DQ<13>
  VSS53  = GND
  DQ16_B  = M_E_CPU1_SB_DQ<16>
  VSS54  = GND
  DQ17_B  = M_E_CPU1_SB_DQ<17>
  VSS55  = GND
  DQS2_B_T  = M_E_CPU1_SB_DQS_DP<2>
  DQS2_B_C  = M_E_CPU1_SB_DQS_DN<2>
  VSS56  = GND
  DQ20_B  = M_E_CPU1_SB_DQ<20>
  VSS57  = GND
  DQ21_B  = M_E_CPU1_SB_DQ<21>
  VSS58  = GND
  DQ24_B  = M_E_CPU1_SB_DQ<24>
  VSS59  = GND
  DQ25_B  = M_E_CPU1_SB_DQ<25>
  VSS60  = GND
  DQS3_B_T  = M_E_CPU1_SB_DQS_DP<3>
  DQS3_B_C  = M_E_CPU1_SB_DQS_DN<3>
  VSS61  = GND
  DQ28_B  = M_E_CPU1_SB_DQ<28>
  VSS62  = GND
  DQ29_B  = M_E_CPU1_SB_DQ<29>
  VSS63  = GND
  RFU1  = TP_CHE_CPU1_DIMM2_FRU_1
  VIN_BULK1  = P12V_S3_AUX_CPU1_NVDIMM
  VIN_BULK2  = P12V_S3_AUX_CPU1_NVDIMM
  \pwr_good||fail_n\  = PWRGD_CHE_CPU1_DIMM2
  HSA  = PD_CHE_CPU1_DIMM2_SAA
  RFU2  = TP_CHE_CPU1_DIMM2_FRU_2
  RFU3  = TP_CHE_CPU1_DIMM2_FRU_3
  VSS64  = GND
  DQ2_A  = M_E_CPU1_SA_DQ<2>
  VSS65  = GND
  DQ3_A  = M_E_CPU1_SA_DQ<3>
  VSS66  = GND
  \dqs5_a_c||tdqs5_a_c||dqs5_a_t||tdqs5_a_t\  = M_E_CPU1_SA_DQS_DN<5>
  \dqs5_a_t||tdqs5_a_t\  = M_E_CPU1_SA_DQS_DP<5>
  VSS67  = GND
  DQ6_A  = M_E_CPU1_SA_DQ<6>
  VSS68  = GND
  DQ7_A  = M_E_CPU1_SA_DQ<7>
  VSS69  = GND
  DQ10_A  = M_E_CPU1_SA_DQ<10>
  VSS70  = GND
  DQ11_A  = M_E_CPU1_SA_DQ<11>
  VSS71  = GND
  \dqs6_a_c||tdqs6_a_c||dqs6_a_t||tdqs6_a_t\  = M_E_CPU1_SA_DQS_DN<6>
  \dqs6_a_t||tdqs6_a_t\  = M_E_CPU1_SA_DQS_DP<6>
  VSS72  = GND
  DQ14_A  = M_E_CPU1_SA_DQ<14>
  VSS73  = GND
  DQ15_A  = M_E_CPU1_SA_DQ<15>
  VSS74  = GND
  DQ18_A  = M_E_CPU1_SA_DQ<18>
  VSS75  = GND
  DQ19_A  = M_E_CPU1_SA_DQ<19>
  VSS76  = GND
  \dqs7_a_c||tdqs7_a_c\  = M_E_CPU1_SA_DQS_DN<7>
  \dqs7_a_t||tdqs7_a_t\  = M_E_CPU1_SA_DQS_DP<7>
  VSS77  = GND
  DQ22_A  = M_E_CPU1_SA_DQ<22>
  VSS78  = GND
  DQ23_A  = M_E_CPU1_SA_DQ<23>
  VSS79  = GND
  DQ26_A  = M_E_CPU1_SA_DQ<26>
  VSS80  = GND
  DQ27_A  = M_E_CPU1_SA_DQ<27>
  VSS81  = GND
  \dqs8_a_c||tdqs8_a_c\  = M_E_CPU1_SA_DQS_DN<8>
  \dqs8_a_t||tdqs8_a_t\  = M_E_CPU1_SA_DQS_DP<8>
  VSS82  = GND
  DQ30_A  = M_E_CPU1_SA_DQ<30>
  VSS83  = GND
  DQ31_A  = M_E_CPU1_SA_DQ<31>
  VSS84  = GND
  CB2_A  = M_E_CPU1_SA_CB<2>
  VSS85  = GND
  CB3_A  = M_E_CPU1_SA_CB<3>
  VSS86  = GND
  \dqs9_a_c||tdqs9_a_c\  = M_E_CPU1_SA_DQS_DN<9>
  \dqs9_a_t||tdqs9_a_t\  = M_E_CPU1_SA_DQS_DP<9>
  VSS87  = GND
  CB6_A  = M_E_CPU1_SA_CB<6>
  VSS88  = GND
  CB7_A  = M_E_CPU1_SA_CB<7>
  VSS89  = GND
  RESET_N  = RST_M_EF_CPU1_FPGA_N
  VSS90  = GND
  CS1_A_N  = M_E_CPU1_SA_CS_N<3>
  VSS91  = GND
  CA1_A  = M_E_CPU1_SA_CA<1>
  VSS92  = GND
  CA3_A  = M_E_CPU1_SA_CA<3>
  VSS93  = GND
  CA5_A  = M_E_CPU1_SA_CA<5>
  VSS94  = GND
  CK_T  = M_E_CPU1_CLK_DP<1>
  CK_C  = M_E_CPU1_CLK_DN<1>
  VSS95  = GND
  RFU4  = TP_CHE_CPU1_DIMM2_FRU_4
  CA1_B  = M_E_CPU1_SB_CA<1>
  VSS96  = GND
  CA3_B  = M_E_CPU1_SB_CA<3>
  VSS97  = GND
  CA5_B  = M_E_CPU1_SB_CA<5>
  VSS98  = GND
  PAR_B  = M_E_CPU1_SB_PAR
  VSS99  = GND
  CS1_B_N  = M_E_CPU1_SB_CS_N<3>
  VSS100  = GND
  RFU5  = TP_CHE_CPU1_DIMM2_FRU_5
  RFU6  = TP_CHE_CPU1_DIMM2_FRU_6
  VSS101  = GND
  CB6_B  = M_E_CPU1_SB_CB<6>
  VSS102  = GND
  CB7_B  = M_E_CPU1_SB_CB<7>
  VSS103  = GND
  DQS4_B_C  = M_E_CPU1_SB_DQS_DN<4>
  DQS4_B_T  = M_E_CPU1_SB_DQS_DP<4>
  VSS104  = GND
  CB2_B  = M_E_CPU1_SB_CB<2>
  VSS105  = GND
  CB3_B  = M_E_CPU1_SB_CB<3>
  VSS106  = GND
  DQ2_B  = M_E_CPU1_SB_DQ<2>
  VSS107  = GND
  DQ3_B  = M_E_CPU1_SB_DQ<3>
  VSS108  = GND
  \dqs5_b_c||tdqs5_b_c\  = M_E_CPU1_SB_DQS_DN<5>
  \dqs5_b_t||tdqs5_b_t\  = M_E_CPU1_SB_DQS_DP<5>
  VSS109  = GND
  DQ6_B  = M_E_CPU1_SB_DQ<6>
  VSS110  = GND
  DQ7_B  = M_E_CPU1_SB_DQ<7>
  VSS111  = GND
  DQ10_B  = M_E_CPU1_SB_DQ<10>
  VSS112  = GND
  DQ11_B  = M_E_CPU1_SB_DQ<11>
  VSS113  = GND
  \dqs6_b_c||tdqs6_b_c\  = M_E_CPU1_SB_DQS_DN<6>
  \dqs6_b_t||tdqs6_b_t\  = M_E_CPU1_SB_DQS_DP<6>
  VSS114  = GND
  DQ14_B  = M_E_CPU1_SB_DQ<14>
  VSS115  = GND
  DQ15_B  = M_E_CPU1_SB_DQ<15>
  VSS116  = GND
  DQ18_B  = M_E_CPU1_SB_DQ<18>
  VSS117  = GND
  DQ19_B  = M_E_CPU1_SB_DQ<19>
  VSS118  = GND
  \dqs7_b_c||tdqs7_b_c\  = M_E_CPU1_SB_DQS_DN<7>
  \dqs7_b_t||tdqs7_b_t\  = M_E_CPU1_SB_DQS_DP<7>
  VSS119  = GND
  DQ22_B  = M_E_CPU1_SB_DQ<22>
  VSS120  = GND
  DQ23_B  = M_E_CPU1_SB_DQ<23>
  VSS121  = GND
  DQ26_B  = M_E_CPU1_SB_DQ<26>
  VSS122  = GND
  DQ27_B  = M_E_CPU1_SB_DQ<27>
  VSS123  = GND
  \dqs8_b_c||tdqs8_b_c\  = M_E_CPU1_SB_DQS_DN<8>
  \dqs8_b_t||tdqs8_b_t\  = M_E_CPU1_SB_DQS_DP<8>
  VSS124  = GND
  DQ30_B  = M_E_CPU1_SB_DQ<30>
  VSS125  = GND
  DQ31_B  = M_E_CPU1_SB_DQ<31>
  VSS126  = GND
  G1  = GND
  G2  = GND
  G3  = GND

(kicad_pcb
	(version 20260206)
	(generator "pcbnew")
	(generator_version "10.0")
	(general
		(thickness 1.6)
		(legacy_teardrops no)
	)
	(paper "A4")
	(title_block
		(title "03242023_DA0F0TMBIJ0_F0T_Motherboard_J_brd_V01_OCP.brd")
		(comment 1 "Grand Teton / footprint 1065 of 6105 (J26), pads 46-91 of 291")
	)
	(layers
		(0 "F.Cu" signal "TOP")
		(4 "In1.Cu" signal "GND")
		(6 "In2.Cu" signal "IN1")
		(8 "In3.Cu" signal "GND1")
		(10 "In4.Cu" signal "IN2")
		(12 "In5.Cu" signal "GND2")
		(14 "In6.Cu" signal "IN3")
		(16 "In7.Cu" signal "GND3")
		(18 "In8.Cu" signal "VCC")
		(20 "In9.Cu" signal "VCC1")
		(22 "In10.Cu" signal "GND4")
		(24 "In11.Cu" signal "IN4")
		(26 "In12.Cu" signal "GND5")
		(28 "In13.Cu" signal "IN5")
		(30 "In14.Cu" signal "GND6")
		(32 "In15.Cu" signal "IN6")
		(34 "In16.Cu" signal "GND7")
		(2 "B.Cu" signal "BOTTOM")
		(9 "F.Adhes" user "F.Adhesive")
		(11 "B.Adhes" user "B.Adhesive")
		(13 "F.Paste" user "Package Geometry/Pastemask Top")
		(15 "B.Paste" user "Package Geometry/Pastemask Bottom")
		(5 "F.SilkS" user "Ref Des/Silkscreen Top")
		(7 "B.SilkS" user "Ref Des/Silkscreen Bottom")
		(1 "F.Mask" user "Board Geometry/Soldermask Top")
		(3 "B.Mask" user "Board Geometry/Soldermask Bottom")
		(17 "Dwgs.User" user "User.Drawings")
		(19 "Cmts.User" user "User.Comments")
		(21 "Eco1.User" user "User.Eco1")
		(23 "Eco2.User" user "User.Eco2")
		(25 "Edge.Cuts" user "Board Geometry/Outline")
		(27 "Margin" user)
		(31 "F.CrtYd" user "Package Geometry/Place Bound Top")
		(29 "B.CrtYd" user "Package Geometry/Place Bound Bottom")
		(35 "F.Fab" user "Ref Des/Assembly Top")
		(33 "B.Fab" user "Ref Des/Assembly Bottom")
	)
	(footprint ""
		(layer "F.Cu")
		(at 160.86328 -258.091686)
		(property "Reference" "J26"
			(at -3.683 -81.702148 0)
			(unlocked yes)
			(layer "F.SilkS")
			(effects
				(font
					(size 0.7874 0.5842)
					(thickness 0.1524)
				)
				(justify left)
			)
		)
		(property "Value" ""
			(at 0 0 0)
			(layer "F.Fab")
			(effects
				(font
					(size 1.27 1.27)
				)
			)
		)
		(duplicate_pad_numbers_are_jumpers no)
		(pad "46" smd rect
			(at -2.050034 -25.07488 270)
			(size 0.519938 1.4986)
			(layers "F.Cu" "F.Mask" "F.Paste")
			(net "GND")
		)
		(pad "47" smd rect
			(at -2.050034 -24.224996 270)
			(size 0.519938 1.4986)
			(layers "F.Cu" "F.Mask" "F.Paste")
			(net "M_E_CPU1_SA_DQ<28>")
		)
		(pad "48" smd rect
			(at -2.050034 -23.375112 270)
			(size 0.519938 1.4986)
			(layers "F.Cu" "F.Mask" "F.Paste")
			(net "GND")
		)
		(pad "49" smd rect
			(at -2.050034 -22.524974 270)
			(size 0.519938 1.4986)
			(layers "F.Cu" "F.Mask" "F.Paste")
			(net "M_E_CPU1_SA_DQ<29>")
		)
		(pad "50" smd rect
			(at -2.050034 -21.67509 270)
			(size 0.519938 1.4986)
			(layers "F.Cu" "F.Mask" "F.Paste")
			(net "GND")
		)
		(pad "51" smd rect
			(at -2.050034 -20.824952 270)
			(size 0.519938 1.4986)
			(layers "F.Cu" "F.Mask" "F.Paste")
			(net "M_E_CPU1_SA_CB<0>")
		)
		(pad "52" smd rect
			(at -2.050034 -19.975068 270)
			(size 0.519938 1.4986)
			(layers "F.Cu" "F.Mask" "F.Paste")
			(net "GND")
		)
		(pad "53" smd rect
			(at -2.050034 -19.12493 270)
			(size 0.519938 1.4986)
			(layers "F.Cu" "F.Mask" "F.Paste")
			(net "M_E_CPU1_SA_CB<1>")
		)
		(pad "54" smd rect
			(at -2.050034 -18.275046 270)
			(size 0.519938 1.4986)
			(layers "F.Cu" "F.Mask" "F.Paste")
			(net "GND")
		)
		(pad "55" smd rect
			(at -2.050034 -17.424908 270)
			(size 0.519938 1.4986)
			(layers "F.Cu" "F.Mask" "F.Paste")
			(net "M_E_CPU1_SA_DQS_DP<4>")
		)
		(pad "56" smd rect
			(at -2.050034 -16.575024 270)
			(size 0.519938 1.4986)
			(layers "F.Cu" "F.Mask" "F.Paste")
			(net "M_E_CPU1_SA_DQS_DN<4>")
		)
		(pad "57" smd rect
			(at -2.050034 -15.724886 270)
			(size 0.519938 1.4986)
			(layers "F.Cu" "F.Mask" "F.Paste")
			(net "GND")
		)
		(pad "58" smd rect
			(at -2.050034 -14.875002 270)
			(size 0.519938 1.4986)
			(layers "F.Cu" "F.Mask" "F.Paste")
			(net "M_E_CPU1_SA_CB<4>")
		)
		(pad "59" smd rect
			(at -2.050034 -14.025118 270)
			(size 0.519938 1.4986)
			(layers "F.Cu" "F.Mask" "F.Paste")
			(net "GND")
		)
		(pad "60" smd rect
			(at -2.050034 -13.17498 270)
			(size 0.519938 1.4986)
			(layers "F.Cu" "F.Mask" "F.Paste")
			(net "M_E_CPU1_SA_CB<5>")
		)
		(pad "61" smd rect
			(at -2.050034 -12.325096 270)
			(size 0.519938 1.4986)
			(layers "F.Cu" "F.Mask" "F.Paste")
			(net "GND")
		)
		(pad "62" smd rect
			(at -2.050034 -11.474958 270)
			(size 0.519938 1.4986)
			(layers "F.Cu" "F.Mask" "F.Paste")
			(net "M_E_CPU1_ALERT_N")
		)
		(pad "63" smd rect
			(at -2.050034 -10.625074 270)
			(size 0.519938 1.4986)
			(layers "F.Cu" "F.Mask" "F.Paste")
			(net "GND")
		)
		(pad "64" smd rect
			(at -2.050034 -9.774936 270)
			(size 0.519938 1.4986)
			(layers "F.Cu" "F.Mask" "F.Paste")
			(net "M_E_CPU1_SA_CS_N<2>")
		)
		(pad "65" smd rect
			(at -2.050034 -8.925052 270)
			(size 0.519938 1.4986)
			(layers "F.Cu" "F.Mask" "F.Paste")
			(net "GND")
		)
		(pad "66" smd rect
			(at -2.050034 -8.074914 270)
			(size 0.519938 1.4986)
			(layers "F.Cu" "F.Mask" "F.Paste")
			(net "M_E_CPU1_SA_CA<0>")
		)
		(pad "67" smd rect
			(at -2.050034 -7.22503 270)
			(size 0.519938 1.4986)
			(layers "F.Cu" "F.Mask" "F.Paste")
			(net "GND")
		)
		(pad "68" smd rect
			(at -2.050034 -6.374892 270)
			(size 0.519938 1.4986)
			(layers "F.Cu" "F.Mask" "F.Paste")
			(net "M_E_CPU1_SA_CA<2>")
		)
		(pad "69" smd rect
			(at -2.050034 -5.525008 270)
			(size 0.519938 1.4986)
			(layers "F.Cu" "F.Mask" "F.Paste")
			(net "GND")
		)
		(pad "70" smd rect
			(at -2.050034 -4.675124 270)
			(size 0.519938 1.4986)
			(layers "F.Cu" "F.Mask" "F.Paste")
			(net "M_E_CPU1_SA_CA<4>")
		)
		(pad "71" smd rect
			(at -2.050034 -3.824986 270)
			(size 0.519938 1.4986)
			(layers "F.Cu" "F.Mask" "F.Paste")
			(net "GND")
		)
		(pad "72" smd rect
			(at -2.050034 -2.975102 270)
			(size 0.519938 1.4986)
			(layers "F.Cu" "F.Mask" "F.Paste")
			(net "M_E_CPU1_SA_CA<6>")
		)
		(pad "73" smd rect
			(at -2.050034 -2.124964 270)
			(size 0.519938 1.4986)
			(layers "F.Cu" "F.Mask" "F.Paste")
			(net "GND")
		)
		(pad "74" smd rect
			(at -2.050034 -1.27508 270)
			(size 0.519938 1.4986)
			(layers "F.Cu" "F.Mask" "F.Paste")
			(net "M_E_CPU1_SA_PAR")
		)
		(pad "75" smd rect
			(at -2.050034 -0.424942 270)
			(size 0.519938 1.4986)
			(layers "F.Cu" "F.Mask" "F.Paste")
			(net "GND")
		)
		(pad "76" smd rect
			(at -2.050034 5.525008 270)
			(size 0.519938 1.4986)
			(layers "F.Cu" "F.Mask" "F.Paste")
			(net "M_E_CPU1_SB_CA<0>")
		)
		(pad "77" smd rect
			(at -2.050034 6.374892 270)
			(size 0.519938 1.4986)
			(layers "F.Cu" "F.Mask" "F.Paste")
			(net "GND")
		)
		(pad "78" smd rect
			(at -2.050034 7.22503 270)
			(size 0.519938 1.4986)
			(layers "F.Cu" "F.Mask" "F.Paste")
			(net "M_E_CPU1_SB_CA<2>")
		)
		(pad "79" smd rect
			(at -2.050034 8.074914 270)
			(size 0.519938 1.4986)
			(layers "F.Cu" "F.Mask" "F.Paste")
			(net "GND")
		)
		(pad "80" smd rect
			(at -2.050034 8.925052 270)
			(size 0.519938 1.4986)
			(layers "F.Cu" "F.Mask" "F.Paste")
			(net "M_E_CPU1_SB_CA<4>")
		)
		(pad "81" smd rect
			(at -2.050034 9.774936 270)
			(size 0.519938 1.4986)
			(layers "F.Cu" "F.Mask" "F.Paste")
			(net "GND")
		)
		(pad "82" smd rect
			(at -2.050034 10.625074 270)
			(size 0.519938 1.4986)
			(layers "F.Cu" "F.Mask" "F.Paste")
			(net "M_E_CPU1_SB_CA<6>")
		)
		(pad "83" smd rect
			(at -2.050034 11.474958 270)
			(size 0.519938 1.4986)
			(layers "F.Cu" "F.Mask" "F.Paste")
			(net "GND")
		)
		(pad "84" smd rect
			(at -2.050034 12.325096 270)
			(size 0.519938 1.4986)
			(layers "F.Cu" "F.Mask" "F.Paste")
			(net "M_E_CPU1_SB_CS_N<2>")
		)
		(pad "85" smd rect
			(at -2.050034 13.17498 270)
			(size 0.519938 1.4986)
			(layers "F.Cu" "F.Mask" "F.Paste")
			(net "GND")
		)
		(pad "86" smd rect
			(at -2.050034 14.025118 270)
			(size 0.519938 1.4986)
			(layers "F.Cu" "F.Mask" "F.Paste")
			(net "M_E_CPU1_SA_RSP<1>")
		)
		(pad "87" smd rect
			(at -2.050034 14.875002 270)
			(size 0.519938 1.4986)
			(layers "F.Cu" "F.Mask" "F.Paste")
			(net "M_E_CPU1_SB_RSP<1>")
		)
		(pad "88" smd rect
			(at -2.050034 15.724886 270)
			(size 0.519938 1.4986)
			(layers "F.Cu" "F.Mask" "F.Paste")
			(net "GND")
		)
		(pad "89" smd rect
			(at -2.050034 16.575024 270)
			(size 0.519938 1.4986)
			(layers "F.Cu" "F.Mask" "F.Paste")
			(net "M_E_CPU1_SB_CB<4>")
		)
		(pad "90" smd rect
			(at -2.050034 17.424908 270)
			(size 0.519938 1.4986)
			(layers "F.Cu" "F.Mask" "F.Paste")
			(net "GND")
		)
		(pad "91" smd rect
			(at -2.050034 18.275046 270)
			(size 0.519938 1.4986)
			(layers "F.Cu" "F.Mask" "F.Paste")
			(net "M_E_CPU1_SB_CB<5>")
		)
	)
)
